(kicad_pcb
	(version 20260206)
	(generator "pcbnew")
	(generator_version "10.0")
	(general
		(thickness 1.6)
		(legacy_teardrops no)
	)
	(paper "A4")
	(title_block
		(title "Bryce Canyon_R.DPB_16317-1_OCP.brd")
		(comment 1 "Bryce Canyon / footprints 1729-1735 of 2099")
	)
	(layers
		(0 "F.Cu" signal "TOP")
		(4 "In1.Cu" signal "L2GND")
		(6 "In2.Cu" signal "L3")
		(8 "In3.Cu" signal "L4VCC")
		(10 "In4.Cu" signal "L5VCC")
		(12 "In5.Cu" signal "L6")
		(14 "In6.Cu" signal "L7GND")
		(2 "B.Cu" signal "BOTTOM")
		(9 "F.Adhes" user "F.Adhesive")
		(11 "B.Adhes" user "B.Adhesive")
		(13 "F.Paste" user "Package Geometry/Pastemask Top")
		(15 "B.Paste" user "Package Geometry/Pastemask Bottom")
		(5 "F.SilkS" user "Ref Des/Silkscreen Top")
		(7 "B.SilkS" user "Ref Des/Silkscreen Bottom")
		(1 "F.Mask" user "Board Geometry/Soldermask Top")
		(3 "B.Mask" user "Board Geometry/Soldermask Bottom")
		(17 "Dwgs.User" user "User.Drawings")
		(19 "Cmts.User" user "User.Comments")
		(21 "Eco1.User" user "User.Eco1")
		(23 "Eco2.User" user "User.Eco2")
		(25 "Edge.Cuts" user "Board Geometry/Outline")
		(27 "Margin" user)
		(31 "F.CrtYd" user "Package Geometry/Place Bound Top")
		(29 "B.CrtYd" user "Package Geometry/Place Bound Bottom")
		(35 "F.Fab" user "Ref Des/Assembly Top")
		(33 "B.Fab" user "Ref Des/Assembly Bottom")
	)
	(footprint ""
		(layer "F.Cu")
		(at 216.140538 -104.671368)
		(property "Reference" "R14"
			(at 0 0 0)
			(layer "F.SilkS")
			(hide yes)
			(effects
				(font
					(size 1.27 1.27)
				)
			)
		)
		(property "Value" "1KR2F-3-GP"
			(at 0.064008 -3.993896 0)
			(unlocked yes)
			(layer "F.Fab")
			(hide yes)
			(effects
				(font
					(size 1.016 1.016)
					(thickness 0.1524)
				)
			)
		)
		(property "Device Type" "R402H16"
			(at 0.064008 -5.517896 0)
			(unlocked yes)
			(layer "F.Fab")
			(hide yes)
			(effects
				(font
					(size 1.016 1.016)
					(thickness 0.1524)
				)
			)
		)
		(duplicate_pad_numbers_are_jumpers no)
		(fp_line
			(start -0.508 -0.9398)
			(end -0.508 0.9398)
			(stroke
				(width 0.1524)
				(type default)
			)
			(layer "F.SilkS")
		)
		(fp_line
			(start 0.508 -0.9398)
			(end -0.508 -0.9398)
			(stroke
				(width 0.1524)
				(type default)
			)
			(layer "F.SilkS")
		)
		(fp_rect
			(start -0.508 0.9398)
			(end 0.508 -0.9398)
			(stroke
				(width 0)
				(type default)
			)
			(fill no)
			(layer "F.CrtYd")
		)
		(fp_rect
			(start -0.508 0.9398)
			(end 0.508 -0.9398)
			(stroke
				(width 0)
				(type default)
			)
			(fill no)
			(layer "F.Fab")
		)
		(pad "1" smd custom
			(at 0 -0.4445)
			(size 0.1397 0.1397)
			(layers "F.Cu" "F.Mask" "F.Paste")
			(net "P3V3_STBY_B")
			(options
				(clearance outline)
				(anchor circle)
			)
			(primitives
				(gr_poly
					(pts
						(arc
							(start -0.1778 -0.2794)
							(mid -0.249642 -0.249642)
							(end -0.2794 -0.1778)
						)
						(arc
							(start -0.2794 0.1778)
							(mid -0.249642 0.249642)
							(end -0.1778 0.2794)
						)
						(arc
							(start 0.1778 0.2794)
							(mid 0.249642 0.249642)
							(end 0.2794 0.1778)
						)
						(arc
							(start 0.2794 -0.1778)
							(mid 0.249642 -0.249642)
							(end 0.1778 -0.2794)
						)
					)
					(width 0)
					(fill yes)
				)
			)
		)
		(pad "2" smd custom
			(at 0 0.4445)
			(size 0.1397 0.1397)
			(layers "F.Cu" "F.Mask" "F.Paste")
			(net "I2C_BMC_A_EXP_B_SCL")
			(options
				(clearance outline)
				(anchor circle)
			)
			(primitives
				(gr_poly
					(pts
						(arc
							(start -0.1778 -0.2794)
							(mid -0.249642 -0.249642)
							(end -0.2794 -0.1778)
						)
						(arc
							(start -0.2794 0.1778)
							(mid -0.249642 0.249642)
							(end -0.1778 0.2794)
						)
						(arc
							(start 0.1778 0.2794)
							(mid 0.249642 0.249642)
							(end 0.2794 0.1778)
						)
						(arc
							(start 0.2794 -0.1778)
							(mid 0.249642 -0.249642)
							(end 0.1778 -0.2794)
						)
					)
					(width 0)
					(fill yes)
				)
			)
		)
	)
	(footprint ""
		(layer "F.Cu")
		(at 334.7212 -13.2842 180)
		(property "Reference" "R774"
			(at 0 0 180)
			(layer "F.SilkS")
			(hide yes)
			(effects
				(font
					(size 1.27 1.27)
				)
			)
		)
		(property "Value" "4K7R2J-2-GP"
			(at 0.064008 -3.993896 180)
			(unlocked yes)
			(layer "F.Fab")
			(hide yes)
			(effects
				(font
					(size 1.016 1.016)
					(thickness 0.1524)
				)
			)
		)
		(property "Device Type" "R402H16"
			(at 0.064008 -5.517896 180)
			(unlocked yes)
			(layer "F.Fab")
			(hide yes)
			(effects
				(font
					(size 1.016 1.016)
					(thickness 0.1524)
				)
			)
		)
		(duplicate_pad_numbers_are_jumpers no)
		(fp_line
			(start 0.508 -0.9398)
			(end -0.508 -0.9398)
			(stroke
				(width 0.1524)
				(type default)
			)
			(layer "F.SilkS")
		)
		(fp_line
			(start -0.508 -0.9398)
			(end -0.508 0.9398)
			(stroke
				(width 0.1524)
				(type default)
			)
			(layer "F.SilkS")
		)
		(fp_rect
			(start -0.508 0.9398)
			(end 0.508 -0.9398)
			(stroke
				(width 0)
				(type default)
			)
			(fill no)
			(layer "F.CrtYd")
		)
		(fp_rect
			(start -0.508 0.9398)
			(end 0.508 -0.9398)
			(stroke
				(width 0)
				(type default)
			)
			(fill no)
			(layer "F.Fab")
		)
		(pad "1" smd custom
			(at 0 -0.4445 180)
			(size 0.1397 0.1397)
			(layers "F.Cu" "F.Mask" "F.Paste")
			(net "P12V_B")
			(options
				(clearance outline)
				(anchor circle)
			)
			(primitives
				(gr_poly
					(pts
						(arc
							(start -0.1778 -0.2794)
							(mid -0.249642 -0.249642)
							(end -0.2794 -0.1778)
						)
						(arc
							(start -0.2794 0.1778)
							(mid -0.249642 0.249642)
							(end -0.1778 0.2794)
						)
						(arc
							(start 0.1778 0.2794)
							(mid 0.249642 0.249642)
							(end 0.2794 0.1778)
						)
						(arc
							(start 0.2794 -0.1778)
							(mid 0.249642 -0.249642)
							(end 0.1778 -0.2794)
						)
					)
					(width 0)
					(fill yes)
				)
			)
		)
		(pad "2" smd custom
			(at 0 0.4445 180)
			(size 0.1397 0.1397)
			(layers "F.Cu" "F.Mask" "F.Paste")
			(net "SW_HDD_R30")
			(options
				(clearance outline)
				(anchor circle)
			)
			(primitives
				(gr_poly
					(pts
						(arc
							(start -0.1778 -0.2794)
							(mid -0.249642 -0.249642)
							(end -0.2794 -0.1778)
						)
						(arc
							(start -0.2794 0.1778)
							(mid -0.249642 0.249642)
							(end -0.1778 0.2794)
						)
						(arc
							(start 0.1778 0.2794)
							(mid 0.249642 0.249642)
							(end 0.2794 0.1778)
						)
						(arc
							(start 0.2794 -0.1778)
							(mid 0.249642 -0.249642)
							(end 0.1778 -0.2794)
						)
					)
					(width 0)
					(fill yes)
				)
			)
		)
	)
	(footprint ""
		(layer "F.Cu")
		(at 86.0806 -248.4628 -90)
		(property "Reference" "R196"
			(at 0 0 270)
			(layer "F.SilkS")
			(hide yes)
			(effects
				(font
					(size 1.27 1.27)
				)
			)
		)
		(property "Value" "1KR2F-3-GP"
			(at 0.064008 -3.993896 270)
			(unlocked yes)
			(layer "F.Fab")
			(hide yes)
			(effects
				(font
					(size 1.016 1.016)
					(thickness 0.1524)
				)
			)
		)
		(property "Device Type" "R402H16"
			(at 0.064008 -5.517896 270)
			(unlocked yes)
			(layer "F.Fab")
			(hide yes)
			(effects
				(font
					(size 1.016 1.016)
					(thickness 0.1524)
				)
			)
		)
		(duplicate_pad_numbers_are_jumpers no)
		(fp_line
			(start -0.508 -0.9398)
			(end -0.508 0.9398)
			(stroke
				(width 0.1524)
				(type default)
			)
			(layer "F.SilkS")
		)
		(fp_line
			(start 0.508 -0.9398)
			(end -0.508 -0.9398)
			(stroke
				(width 0.1524)
				(type default)
			)
			(layer "F.SilkS")
		)
		(fp_rect
			(start -0.508 0.9398)
			(end 0.508 -0.9398)
			(stroke
				(width 0)
				(type default)
			)
			(fill no)
			(layer "F.CrtYd")
		)
		(fp_rect
			(start -0.508 0.9398)
			(end 0.508 -0.9398)
			(stroke
				(width 0)
				(type default)
			)
			(fill no)
			(layer "F.Fab")
		)
		(pad "1" smd custom
			(at 0 -0.4445 270)
			(size 0.1397 0.1397)
			(layers "F.Cu" "F.Mask" "F.Paste")
			(net "P3V3_STBY_B")
			(options
				(clearance outline)
				(anchor circle)
			)
			(primitives
				(gr_poly
					(pts
						(arc
							(start -0.1778 -0.2794)
							(mid -0.249642 -0.249642)
							(end -0.2794 -0.1778)
						)
						(arc
							(start -0.2794 0.1778)
							(mid -0.249642 0.249642)
							(end -0.1778 0.2794)
						)
						(arc
							(start 0.1778 0.2794)
							(mid 0.249642 0.249642)
							(end 0.2794 0.1778)
						)
						(arc
							(start 0.2794 -0.1778)
							(mid 0.249642 -0.249642)
							(end 0.1778 -0.2794)
						)
					)
					(width 0)
					(fill yes)
				)
			)
		)
		(pad "2" smd custom
			(at 0 0.4445 270)
			(size 0.1397 0.1397)
			(layers "F.Cu" "F.Mask" "F.Paste")
			(net "SW_PWR_R_HDD2")
			(options
				(clearance outline)
				(anchor circle)
			)
			(primitives
				(gr_poly
					(pts
						(arc
							(start -0.1778 -0.2794)
							(mid -0.249642 -0.249642)
							(end -0.2794 -0.1778)
						)
						(arc
							(start -0.2794 0.1778)
							(mid -0.249642 0.249642)
							(end -0.1778 0.2794)
						)
						(arc
							(start 0.1778 0.2794)
							(mid 0.249642 0.249642)
							(end 0.2794 0.1778)
						)
						(arc
							(start 0.2794 -0.1778)
							(mid 0.249642 -0.249642)
							(end 0.1778 -0.2794)
						)
					)
					(width 0)
					(fill yes)
				)
			)
		)
	)
	(footprint ""
		(layer "F.Cu")
		(at 83.185 -32.004 -90)
		(property "Reference" "C369"
			(at 0 0 270)
			(layer "F.SilkS")
			(hide yes)
			(effects
				(font
					(size 1.27 1.27)
				)
			)
		)
		(property "Value" "SC10U16V6KX-2GP"
			(at -0.0762 -5.1308 270)
			(unlocked yes)
			(layer "F.Fab")
			(hide yes)
			(effects
				(font
					(size 1.016 1.016)
					(thickness 0.1524)
				)
			)
		)
		(property "Device Type" "C1206H71"
			(at -0.127 -6.6548 270)
			(unlocked yes)
			(layer "F.Fab")
			(hide yes)
			(effects
				(font
					(size 1.016 1.016)
					(thickness 0.1524)
				)
			)
		)
		(duplicate_pad_numbers_are_jumpers no)
		(fp_line
			(start -1.016 2.2352)
			(end -1.016 0.8382)
			(stroke
				(width 0.1524)
				(type default)
			)
			(layer "F.SilkS")
		)
		(fp_line
			(start 1.016 2.2352)
			(end -1.016 2.2352)
			(stroke
				(width 0.1524)
				(type default)
			)
			(layer "F.SilkS")
		)
		(fp_line
			(start 1.016 0.8382)
			(end 1.016 2.2352)
			(stroke
				(width 0.1524)
				(type default)
			)
			(layer "F.SilkS")
		)
		(fp_line
			(start -1.016 -0.8382)
			(end -1.016 -2.2352)
			(stroke
				(width 0.1524)
				(type default)
			)
			(layer "F.SilkS")
		)
		(fp_line
			(start -1.016 -2.2352)
			(end 1.016 -2.2352)
			(stroke
				(width 0.1524)
				(type default)
			)
			(layer "F.SilkS")
		)
		(fp_line
			(start 1.016 -2.2352)
			(end 1.016 -0.8382)
			(stroke
				(width 0.1524)
				(type default)
			)
			(layer "F.SilkS")
		)
		(fp_rect
			(start -1.0922 2.3114)
			(end 1.0922 -2.3114)
			(stroke
				(width 0)
				(type default)
			)
			(fill no)
			(layer "F.CrtYd")
		)
		(fp_poly
			(pts
				(xy 1.0922 -2.3114) (xy 1.0922 2.3114) (xy -1.0922 2.3114) (xy -1.0922 -2.3114)
			)
			(stroke
				(width 0)
				(type default)
			)
			(fill no)
			(layer "F.Fab")
		)
		(pad "1" smd rect
			(at 0 -1.397 270)
			(size 1.651 1.27)
			(layers "F.Cu" "F.Mask" "F.Paste")
			(net "P5V_HDD26")
		)
		(pad "2" smd rect
			(at 0 1.397 270)
			(size 1.651 1.27)
			(layers "F.Cu" "F.Mask" "F.Paste")
			(net "GND")
		)
	)
	(footprint ""
		(layer "F.Cu")
		(at 44.1706 -6.3754 -90)
		(property "Reference" "R130"
			(at 0 0 270)
			(layer "F.SilkS")
			(hide yes)
			(effects
				(font
					(size 1.27 1.27)
				)
			)
		)
		(property "Value" "4K7R2F-GP"
			(at 0.064008 -3.993896 270)
			(unlocked yes)
			(layer "F.Fab")
			(hide yes)
			(effects
				(font
					(size 1.016 1.016)
					(thickness 0.1524)
				)
			)
		)
		(property "Device Type" "R402H16"
			(at 0.064008 -5.517896 270)
			(unlocked yes)
			(layer "F.Fab")
			(hide yes)
			(effects
				(font
					(size 1.016 1.016)
					(thickness 0.1524)
				)
			)
		)
		(duplicate_pad_numbers_are_jumpers no)
		(fp_line
			(start -0.508 -0.9398)
			(end -0.508 0.9398)
			(stroke
				(width 0.1524)
				(type default)
			)
			(layer "F.SilkS")
		)
		(fp_line
			(start 0.508 -0.9398)
			(end -0.508 -0.9398)
			(stroke
				(width 0.1524)
				(type default)
			)
			(layer "F.SilkS")
		)
		(fp_rect
			(start -0.508 0.9398)
			(end 0.508 -0.9398)
			(stroke
				(width 0)
				(type default)
			)
			(fill no)
			(layer "F.CrtYd")
		)
		(fp_rect
			(start -0.508 0.9398)
			(end 0.508 -0.9398)
			(stroke
				(width 0)
				(type default)
			)
			(fill no)
			(layer "F.Fab")
		)
		(pad "1" smd custom
			(at 0 -0.4445 270)
			(size 0.1397 0.1397)
			(layers "F.Cu" "F.Mask" "F.Paste")
			(net "P3V3_STBY_A")
			(options
				(clearance outline)
				(anchor circle)
			)
			(primitives
				(gr_poly
					(pts
						(arc
							(start -0.1778 -0.2794)
							(mid -0.249642 -0.249642)
							(end -0.2794 -0.1778)
						)
						(arc
							(start -0.2794 0.1778)
							(mid -0.249642 0.249642)
							(end -0.1778 0.2794)
						)
						(arc
							(start 0.1778 0.2794)
							(mid 0.249642 0.249642)
							(end 0.2794 0.1778)
						)
						(arc
							(start 0.2794 -0.1778)
							(mid 0.249642 -0.249642)
							(end 0.1778 -0.2794)
						)
					)
					(width 0)
					(fill yes)
				)
			)
		)
		(pad "2" smd custom
			(at 0 0.4445 270)
			(size 0.1397 0.1397)
			(layers "F.Cu" "F.Mask" "F.Paste")
			(net "TEMP1_A1")
			(options
				(clearance outline)
				(anchor circle)
			)
			(primitives
				(gr_poly
					(pts
						(arc
							(start -0.1778 -0.2794)
							(mid -0.249642 -0.249642)
							(end -0.2794 -0.1778)
						)
						(arc
							(start -0.2794 0.1778)
							(mid -0.249642 0.249642)
							(end -0.1778 0.2794)
						)
						(arc
							(start 0.1778 0.2794)
							(mid 0.249642 0.249642)
							(end 0.2794 0.1778)
						)
						(arc
							(start 0.2794 -0.1778)
							(mid 0.249642 -0.249642)
							(end 0.1778 -0.2794)
						)
					)
					(width 0)
					(fill yes)
				)
			)
		)
	)
	(footprint ""
		(layer "F.Cu")
		(at 260.546596 -238.583724 -90)
		(property "Reference" "R497"
			(at 0 0 270)
			(layer "F.SilkS")
			(hide yes)
			(effects
				(font
					(size 1.27 1.27)
				)
			)
		)
		(property "Value" "10KR2F-2-GP"
			(at 0.064008 -3.993896 270)
			(unlocked yes)
			(layer "F.Fab")
			(hide yes)
			(effects
				(font
					(size 1.016 1.016)
					(thickness 0.1524)
				)
			)
		)
		(property "Device Type" "R402H16"
			(at 0.064008 -5.517896 270)
			(unlocked yes)
			(layer "F.Fab")
			(hide yes)
			(effects
				(font
					(size 1.016 1.016)
					(thickness 0.1524)
				)
			)
		)
		(duplicate_pad_numbers_are_jumpers no)
		(fp_line
			(start -0.508 -0.9398)
			(end -0.508 0.9398)
			(stroke
				(width 0.1524)
				(type default)
			)
			(layer "F.SilkS")
		)
		(fp_line
			(start 0.508 -0.9398)
			(end -0.508 -0.9398)
			(stroke
				(width 0.1524)
				(type default)
			)
			(layer "F.SilkS")
		)
		(fp_rect
			(start -0.508 0.9398)
			(end 0.508 -0.9398)
			(stroke
				(width 0)
				(type default)
			)
			(fill no)
			(layer "F.CrtYd")
		)
		(fp_rect
			(start -0.508 0.9398)
			(end 0.508 -0.9398)
			(stroke
				(width 0)
				(type default)
			)
			(fill no)
			(layer "F.Fab")
		)
		(pad "1" smd custom
			(at 0 -0.4445 270)
			(size 0.1397 0.1397)
			(layers "F.Cu" "F.Mask" "F.Paste")
			(net "P12V_B")
			(options
				(clearance outline)
				(anchor circle)
			)
			(primitives
				(gr_poly
					(pts
						(arc
							(start -0.1778 -0.2794)
							(mid -0.249642 -0.249642)
							(end -0.2794 -0.1778)
						)
						(arc
							(start -0.2794 0.1778)
							(mid -0.249642 0.249642)
							(end -0.1778 0.2794)
						)
						(arc
							(start 0.1778 0.2794)
							(mid 0.249642 0.249642)
							(end 0.2794 0.1778)
						)
						(arc
							(start 0.2794 -0.1778)
							(mid 0.249642 -0.249642)
							(end 0.1778 -0.2794)
						)
					)
					(width 0)
					(fill yes)
				)
			)
		)
		(pad "2" smd custom
			(at 0 0.4445 270)
			(size 0.1397 0.1397)
			(layers "F.Cu" "F.Mask" "F.Paste")
			(net "SCC_B_FULL_PWR_EN_12V")
			(options
				(clearance outline)
				(anchor circle)
			)
			(primitives
				(gr_poly
					(pts
						(arc
							(start -0.1778 -0.2794)
							(mid -0.249642 -0.249642)
							(end -0.2794 -0.1778)
						)
						(arc
							(start -0.2794 0.1778)
							(mid -0.249642 0.249642)
							(end -0.1778 0.2794)
						)
						(arc
							(start 0.1778 0.2794)
							(mid 0.249642 0.249642)
							(end 0.2794 0.1778)
						)
						(arc
							(start 0.2794 -0.1778)
							(mid 0.249642 -0.249642)
							(end 0.1778 -0.2794)
						)
					)
					(width 0)
					(fill yes)
				)
			)
		)
	)
	(footprint ""
		(layer "F.Cu")
		(at 303.249076 -340.812882)
		(property "Reference" "R94"
			(at 0 0 0)
			(layer "F.SilkS")
			(hide yes)
			(effects
				(font
					(size 1.27 1.27)
				)
			)
		)
		(property "Value" "4K7R2F-GP"
			(at 0.064008 -3.993896 0)
			(unlocked yes)
			(layer "F.Fab")
			(hide yes)
			(effects
				(font
					(size 1.016 1.016)
					(thickness 0.1524)
				)
			)
		)
		(property "Device Type" "R402H16"
			(at 0.064008 -5.517896 0)
			(unlocked yes)
			(layer "F.Fab")
			(hide yes)
			(effects
				(font
					(size 1.016 1.016)
					(thickness 0.1524)
				)
			)
		)
		(duplicate_pad_numbers_are_jumpers no)
		(fp_line
			(start -0.508 -0.9398)
			(end -0.508 0.9398)
			(stroke
				(width 0.1524)
				(type default)
			)
			(layer "F.SilkS")
		)
		(fp_line
			(start 0.508 -0.9398)
			(end -0.508 -0.9398)
			(stroke
				(width 0.1524)
				(type default)
			)
			(layer "F.SilkS")
		)
		(fp_rect
			(start -0.508 0.9398)
			(end 0.508 -0.9398)
			(stroke
				(width 0)
				(type default)
			)
			(fill no)
			(layer "F.CrtYd")
		)
		(fp_rect
			(start -0.508 0.9398)
			(end 0.508 -0.9398)
			(stroke
				(width 0)
				(type default)
			)
			(fill no)
			(layer "F.Fab")
		)
		(pad "1" smd custom
			(at 0 -0.4445)
			(size 0.1397 0.1397)
			(layers "F.Cu" "F.Mask" "F.Paste")
			(net "P3V3_IN")
			(options
				(clearance outline)
				(anchor circle)
			)
			(primitives
				(gr_poly
					(pts
						(arc
							(start -0.1778 -0.2794)
							(mid -0.249642 -0.249642)
							(end -0.2794 -0.1778)
						)
						(arc
							(start -0.2794 0.1778)
							(mid -0.249642 0.249642)
							(end -0.1778 0.2794)
						)
						(arc
							(start 0.1778 0.2794)
							(mid 0.249642 0.249642)
							(end 0.2794 0.1778)
						)
						(arc
							(start 0.2794 -0.1778)
							(mid 0.249642 -0.249642)
							(end 0.1778 -0.2794)
						)
					)
					(width 0)
					(fill yes)
				)
			)
		)
		(pad "2" smd custom
			(at 0 0.4445)
			(size 0.1397 0.1397)
			(layers "F.Cu" "F.Mask" "F.Paste")
			(net "THERMHOT#_C")
			(options
				(clearance outline)
				(anchor circle)
			)
			(primitives
				(gr_poly
					(pts
						(arc
							(start -0.1778 -0.2794)
							(mid -0.249642 -0.249642)
							(end -0.2794 -0.1778)
						)
						(arc
							(start -0.2794 0.1778)
							(mid -0.249642 0.249642)
							(end -0.1778 0.2794)
						)
						(arc
							(start 0.1778 0.2794)
							(mid 0.249642 0.249642)
							(end 0.2794 0.1778)
						)
						(arc
							(start 0.2794 -0.1778)
							(mid 0.249642 -0.249642)
							(end 0.1778 -0.2794)
						)
					)
					(width 0)
					(fill yes)
				)
			)
		)
	)
)
